#ISCELL
  mstr_misc prelim *
  *
#ISCELL
  mstr_symbols design_note *
  *
#ISCELL
  mstr_symbols intel_corp_bpage *
  *
#ISCELL
  mstr_standard offpage *
  page24_i1
#ISCELL
  mstr_standard tap *
  page24_i10
#ISCELL
  mstr_standard tap *
  page24_i100
#ISCELL
  mstr_standard tap *
  page24_i101
#ISCELL
  mstr_standard tap *
  page24_i102
#ISCELL
  mstr_standard tap *
  page24_i103
#ISCELL
  mstr_standard tap *
  page24_i104
#ISCELL
  mstr_standard tap *
  page24_i105
#ISCELL
  mstr_standard tap *
  page24_i106
#ISCELL
  mstr_standard tap *
  page24_i107
#ISCELL
  mstr_standard tap *
  page24_i108
#ISCELL
  mstr_standard tap *
  page24_i109
#ISCELL
  mstr_standard tap *
  page24_i11
#ISCELL
  mstr_standard tap *
  page24_i110
#ISCELL
  mstr_standard tap *
  page24_i111
#ISCELL
  mstr_standard tap *
  page24_i112
#ISCELL
  mstr_standard tap *
  page24_i113
#ISCELL
  mstr_standard tap *
  page24_i114
#ISCELL
  mstr_standard tap *
  page24_i115
#ISCELL
  mstr_standard tap *
  page24_i116
#ISCELL
  mstr_standard tap *
  page24_i117
#ISCELL
  mstr_standard tap *
  page24_i118
#ISCELL
  mstr_standard tap *
  page24_i119
#ISCELL
  mstr_standard tap *
  page24_i12
#ISCELL
  mstr_standard tap *
  page24_i120
#ISCELL
  mstr_standard tap *
  page24_i121
#ISCELL
  mstr_standard tap *
  page24_i122
#ISCELL
  mstr_standard tap *
  page24_i123
#ISCELL
  mstr_standard tap *
  page24_i124
#ISCELL
  mstr_standard tap *
  page24_i125
#ISCELL
  mstr_standard tap *
  page24_i126
#ISCELL
  mstr_standard tap *
  page24_i127
#ISCELL
  mstr_standard tap *
  page24_i128
#ISCELL
  mstr_standard tap *
  page24_i129
#ISCELL
  mstr_standard tap *
  page24_i13
#ISCELL
  mstr_standard tap *
  page24_i130
#ISCELL
  mstr_standard tap *
  page24_i131
#ISCELL
  mstr_standard tap *
  page24_i132
#ISCELL
  mstr_standard tap *
  page24_i133
#ISCELL
  mstr_standard tap *
  page24_i134
#ISCELL
  mstr_standard tap *
  page24_i135
#ISCELL
  mstr_standard tap *
  page24_i136
#ISCELL
  mstr_standard tap *
  page24_i137
#ISCELL
  mstr_standard tap *
  page24_i138
#ISCELL
  mstr_standard tap *
  page24_i139
#ISCELL
  mstr_standard tap *
  page24_i14
#ISCELL
  mstr_standard tap *
  page24_i140
#ISCELL
  mstr_standard tap *
  page24_i141
#ISCELL
  mstr_standard tap *
  page24_i142
#ISCELL
  mstr_standard tap *
  page24_i143
#ISCELL
  mstr_standard tap *
  page24_i144
#ISCELL
  mstr_standard tap *
  page24_i145
#ISCELL
  mstr_standard tap *
  page24_i146
#ISCELL
  mstr_standard offpage *
  page24_i147
#ISCELL
  mstr_standard offpage *
  page24_i148
#ISCELL
  mstr_standard offpage *
  page24_i149
#ISCELL
  mstr_standard tap *
  page24_i15
#ISCELL
  mstr_standard offpage *
  page24_i150
#ISCELL
  mstr_standard offpage *
  page24_i151
#ISCELL
  mstr_standard offpage *
  page24_i152
#ISCELL
  mstr_standard offpage *
  page24_i153
#ISCELL
  mstr_standard offpage *
  page24_i154
#ISCELL
  mstr_standard offpage *
  page24_i155
#ISCELL
  mstr_standard offpage *
  page24_i156
#ISCELL
  mstr_standard tap *
  page24_i157
#ISCELL
  mstr_standard tap *
  page24_i158
#ISCELL
  mstr_standard tap *
  page24_i159
#ISCELL
  mstr_standard tap *
  page24_i16
#ISCELL
  mstr_standard tap *
  page24_i160
#ISCELL
  mstr_standard tap *
  page24_i161
#ISCELL
  mstr_standard tap *
  page24_i162
#ISCELL
  mstr_standard tap *
  page24_i163
#ISCELL
  mstr_standard tap *
  page24_i164
#ISCELL
  mstr_standard tap *
  page24_i165
#ISCELL
  mstr_standard tap *
  page24_i166
#ISCELL
  mstr_standard tap *
  page24_i167
#ISCELL
  mstr_standard tap *
  page24_i168
#ISCELL
  mstr_standard tap *
  page24_i169
#ISCELL
  mstr_standard tap *
  page24_i17
#ISCELL
  mstr_standard tap *
  page24_i170
#ISCELL
  mstr_standard offpage *
  page24_i171
#CELL
  chpset_lib skx_ext_b *
  page24_i172
#ISCELL
  mstr_standard tap *
  page24_i18
#ISCELL
  mstr_standard tap *
  page24_i19
#ISCELL
  mstr_standard offpage *
  page24_i2
#ISCELL
  mstr_standard tap *
  page24_i20
#ISCELL
  mstr_standard tap *
  page24_i21
#ISCELL
  mstr_standard tap *
  page24_i22
#ISCELL
  mstr_standard tap *
  page24_i23
#ISCELL
  mstr_standard tap *
  page24_i24
#ISCELL
  mstr_standard tap *
  page24_i25
#ISCELL
  mstr_standard tap *
  page24_i26
#ISCELL
  mstr_standard tap *
  page24_i27
#ISCELL
  mstr_standard tap *
  page24_i28
#ISCELL
  mstr_standard tap *
  page24_i29
#ISCELL
  mstr_standard offpage *
  page24_i3
#ISCELL
  mstr_standard tap *
  page24_i31
#ISCELL
  mstr_standard tap *
  page24_i32
#ISCELL
  mstr_standard tap *
  page24_i33
#ISCELL
  mstr_standard tap *
  page24_i34
#ISCELL
  mstr_standard tap *
  page24_i35
#ISCELL
  mstr_standard tap *
  page24_i36
#ISCELL
  mstr_standard tap *
  page24_i37
#ISCELL
  mstr_standard tap *
  page24_i38
#ISCELL
  mstr_standard tap *
  page24_i39
#ISCELL
  mstr_standard offpage *
  page24_i4
#ISCELL
  mstr_standard tap *
  page24_i40
#ISCELL
  mstr_standard tap *
  page24_i41
#ISCELL
  mstr_standard tap *
  page24_i42
#ISCELL
  mstr_standard tap *
  page24_i43
#ISCELL
  mstr_standard tap *
  page24_i44
#ISCELL
  mstr_standard tap *
  page24_i45
#ISCELL
  mstr_standard tap *
  page24_i46
#ISCELL
  mstr_standard tap *
  page24_i47
#ISCELL
  mstr_standard tap *
  page24_i48
#ISCELL
  mstr_standard tap *
  page24_i49
#ISCELL
  mstr_standard tap *
  page24_i5
#ISCELL
  mstr_standard tap *
  page24_i50
#ISCELL
  mstr_standard tap *
  page24_i51
#ISCELL
  mstr_standard tap *
  page24_i52
#ISCELL
  mstr_standard tap *
  page24_i53
#ISCELL
  mstr_standard tap *
  page24_i54
#ISCELL
  mstr_standard tap *
  page24_i55
#ISCELL
  mstr_standard tap *
  page24_i56
#ISCELL
  mstr_standard tap *
  page24_i57
#ISCELL
  mstr_standard tap *
  page24_i58
#ISCELL
  mstr_standard tap *
  page24_i59
#ISCELL
  mstr_standard tap *
  page24_i6
#ISCELL
  mstr_standard tap *
  page24_i60
#ISCELL
  mstr_standard tap *
  page24_i61
#ISCELL
  mstr_standard tap *
  page24_i62
#ISCELL
  mstr_standard tap *
  page24_i63
#ISCELL
  mstr_standard tap *
  page24_i64
#ISCELL
  mstr_standard tap *
  page24_i65
#ISCELL
  mstr_standard tap *
  page24_i66
#ISCELL
  mstr_standard tap *
  page24_i67
#ISCELL
  mstr_standard tap *
  page24_i68
#ISCELL
  mstr_standard tap *
  page24_i69
#ISCELL
  mstr_standard tap *
  page24_i7
#ISCELL
  mstr_standard tap *
  page24_i70
#ISCELL
  mstr_standard tap *
  page24_i71
#ISCELL
  mstr_standard offpage *
  page24_i72
#ISCELL
  mstr_standard tap *
  page24_i73
#ISCELL
  mstr_standard tap *
  page24_i74
#ISCELL
  mstr_standard tap *
  page24_i75
#ISCELL
  mstr_standard tap *
  page24_i76
#ISCELL
  mstr_standard tap *
  page24_i77
#ISCELL
  mstr_standard tap *
  page24_i78
#ISCELL
  mstr_standard tap *
  page24_i79
#ISCELL
  mstr_standard tap *
  page24_i8
#ISCELL
  mstr_standard tap *
  page24_i80
#ISCELL
  mstr_standard tap *
  page24_i81
#ISCELL
  mstr_standard tap *
  page24_i82
#ISCELL
  mstr_standard tap *
  page24_i83
#ISCELL
  mstr_standard tap *
  page24_i84
#ISCELL
  mstr_standard tap *
  page24_i85
#ISCELL
  mstr_standard tap *
  page24_i86
#ISCELL
  mstr_standard tap *
  page24_i87
#ISCELL
  mstr_standard tap *
  page24_i88
#ISCELL
  mstr_standard tap *
  page24_i89
#ISCELL
  mstr_standard tap *
  page24_i9
#ISCELL
  mstr_standard tap *
  page24_i90
#ISCELL
  mstr_standard tap *
  page24_i91
#ISCELL
  mstr_standard tap *
  page24_i92
#ISCELL
  mstr_standard tap *
  page24_i93
#ISCELL
  mstr_standard tap *
  page24_i94
#ISCELL
  mstr_standard tap *
  page24_i95
#ISCELL
  mstr_standard tap *
  page24_i96
#ISCELL
  mstr_standard tap *
  page24_i97
#ISCELL
  mstr_standard tap *
  page24_i98
#ISCELL
  mstr_standard tap *
  page24_i99
